# TIMECARD (Time Appliance Project (Time Card)) — schematic netlist excerpt (pin names and nets, part order shuffled) for the footprints in the layout excerpt that follows; sources: Cadence DE-HDL packaged netlist, KiCad conversion of R4006-B0001-02_R01.brd

TP51  TP_PIONT  pkg TP010CT020B030_PTH  page 25 : \1\ = MAC_ALARM
R308  RESISTOR  10KOHM 1%  pkg SMC_0402R_H016  page 25 : \1\ = XP3R3V_FPGA ; \2\ = FPGA_IO_5

(kicad_pcb
	(version 20260206)
	(generator "pcbnew")
	(generator_version "10.0")
	(general
		(thickness 1.6)
		(legacy_teardrops no)
	)
	(paper "A4")
	(title_block
		(title "timecard-production-celestica-r4006 — R4006-B0001-02_R01.brd")
		(comment 1 "Time Appliance Project (Time Card) / footprints 594-595 of 1113")
	)
	(layers
		(0 "F.Cu" signal "TOP")
		(4 "In1.Cu" signal "L02_GND1")
		(6 "In2.Cu" signal "L03_SIG1")
		(8 "In3.Cu" signal "L04_GND2")
		(10 "In4.Cu" signal "L05_VCC1")
		(12 "In5.Cu" signal "L06_VCC2")
		(14 "In6.Cu" signal "L07_GND3")
		(16 "In7.Cu" signal "L08_SIG2")
		(18 "In8.Cu" signal "L09_GND4")
		(2 "B.Cu" signal "BOTTOM")
		(9 "F.Adhes" user "F.Adhesive")
		(11 "B.Adhes" user "B.Adhesive")
		(13 "F.Paste" user "Package Geometry/Pastemask Top")
		(15 "B.Paste" user "Package Geometry/Pastemask Bottom")
		(5 "F.SilkS" user "Ref Des/Silkscreen Top")
		(7 "B.SilkS" user "Ref Des/Silkscreen Bottom")
		(1 "F.Mask" user "Board Geometry/Soldermask Top")
		(3 "B.Mask" user "Board Geometry/Soldermask Bottom")
		(17 "Dwgs.User" user "User.Drawings")
		(19 "Cmts.User" user "User.Comments")
		(21 "Eco1.User" user "User.Eco1")
		(23 "Eco2.User" user "User.Eco2")
		(25 "Edge.Cuts" user "Board Geometry/Outline")
		(27 "Margin" user)
		(31 "F.CrtYd" user "Package Geometry/Place Bound Top")
		(29 "B.CrtYd" user "Package Geometry/Place Bound Bottom")
		(35 "F.Fab" user "Ref Des/Assembly Top")
		(33 "B.Fab" user "Ref Des/Assembly Bottom")
	)
	(footprint ""
		(layer "F.Cu")
		(at 103.9622 -64.2874 -90)
		(property "Reference" "R308"
			(at 2.6924 -0.85217 90)
			(unlocked yes)
			(layer "F.SilkS")
			(effects
				(font
					(size 0.7874 0.5842)
					(thickness 0.1524)
				)
			)
		)
		(property "Value" "VAL*"
			(at 0.02032 2.13233 270)
			(unlocked yes)
			(layer "F.Fab")
			(hide yes)
			(effects
				(font
					(size 0.7874 0.5842)
					(thickness 0.1524)
				)
			)
		)
		(property "Tolerance" "TOL*"
			(at 0.044704 3.05435 270)
			(unlocked yes)
			(layer "Cmts.User")
			(hide yes)
			(effects
				(font
					(size 0.7874 0.5842)
					(thickness 0.1524)
				)
			)
		)
		(property "User Part Number" "PARTNUM*"
			(at 0.02032 4.024884 270)
			(unlocked yes)
			(layer "Cmts.User")
			(hide yes)
			(effects
				(font
					(size 0.7874 0.5842)
					(thickness 0.1524)
				)
			)
		)
		(property "Device Type" "RESISTOR-G155-11002-01,10KOHM,A"
			(at 0.008382 1.210564 270)
			(unlocked yes)
			(layer "F.Fab")
			(hide yes)
			(effects
				(font
					(size 0.7874 0.5842)
					(thickness 0.1524)
				)
			)
		)
		(duplicate_pad_numbers_are_jumpers no)
		(fp_line
			(start -1.143 0.5588)
			(end 1.143 0.5588)
			(stroke
				(width 0.1)
				(type default)
			)
			(layer "F.SilkS")
		)
		(fp_line
			(start 1.143 0.5588)
			(end 1.143 -0.5588)
			(stroke
				(width 0.1)
				(type default)
			)
			(layer "F.SilkS")
		)
		(fp_line
			(start -1.143 -0.5588)
			(end -1.143 0.5588)
			(stroke
				(width 0.1)
				(type default)
			)
			(layer "F.SilkS")
		)
		(fp_line
			(start 1.143 -0.5588)
			(end -1.143 -0.5588)
			(stroke
				(width 0.1)
				(type default)
			)
			(layer "F.SilkS")
		)
		(fp_poly
			(pts
				(xy -1.143 0.5588) (xy 1.143 0.5588) (xy 1.143 -0.5588) (xy -1.143 -0.5588)
			)
			(stroke
				(width 0)
				(type default)
			)
			(fill no)
			(layer "F.CrtYd")
		)
		(fp_line
			(start -0.508 0.3048)
			(end 0.508 0.3048)
			(stroke
				(width 0.1)
				(type default)
			)
			(layer "F.Fab")
		)
		(fp_line
			(start 0.508 0.3048)
			(end 0.508 -0.3048)
			(stroke
				(width 0.1)
				(type default)
			)
			(layer "F.Fab")
		)
		(fp_line
			(start -0.508 -0.3048)
			(end -0.508 0.3048)
			(stroke
				(width 0.1)
				(type default)
			)
			(layer "F.Fab")
		)
		(fp_line
			(start 0.508 -0.3048)
			(end -0.508 -0.3048)
			(stroke
				(width 0.1)
				(type default)
			)
			(layer "F.Fab")
		)
		(pad "1" smd rect
			(at -0.5334 0 270)
			(size 0.7112 0.6096)
			(layers "F.Cu" "F.Mask" "F.Paste")
			(net "XP3R3V_FPGA")
		)
		(pad "2" smd rect
			(at 0.5334 0 270)
			(size 0.7112 0.6096)
			(layers "F.Cu" "F.Mask" "F.Paste")
			(net "FPGA_IO_5")
		)
		(zone
			(layer "F.Cu")
			(hatch none 0.5)
			(connect_pads
				(clearance 0)
			)
			(min_thickness 0.25)
			(keepout
				(tracks not_allowed)
				(vias allowed)
				(pads allowed)
				(copperpour not_allowed)
				(footprints allowed)
			)
			(placement
				(enabled no)
				(sheetname "")
			)
			(fill
				(thermal_gap 0.5)
				(thermal_bridge_width 0.5)
				(island_removal_mode 0)
			)
			(polygon
				(pts
					(xy 103.6574 -64.3636) (xy 103.6574 -64.2112) (xy 104.267 -64.2112) (xy 104.267 -64.3636)
				)
			)
		)
		(zone
			(layer "F.Cu")
			(hatch none 0.5)
			(connect_pads
				(clearance 0)
			)
			(min_thickness 0.25)
			(keepout
				(tracks allowed)
				(vias not_allowed)
				(pads allowed)
				(copperpour not_allowed)
				(footprints allowed)
			)
			(placement
				(enabled no)
				(sheetname "")
			)
			(fill
				(thermal_gap 0.5)
				(thermal_bridge_width 0.5)
				(island_removal_mode 0)
			)
			(polygon
				(pts
					(xy 103.6574 -64.3636) (xy 103.6574 -64.2112) (xy 104.267 -64.2112) (xy 104.267 -64.3636)
				)
			)
		)
	)
	(footprint ""
		(layer "F.Cu")
		(at 77.851 -43.053)
		(property "Reference" "TP51"
			(at -1.48463 2.8702 90)
			(unlocked yes)
			(layer "F.SilkS")
			(effects
				(font
					(size 0.7874 0.5842)
					(thickness 0.1524)
				)
				(justify left)
			)
		)
		(property "Value" ""
			(at 0 0 0)
			(layer "F.Fab")
			(effects
				(font
					(size 1.27 1.27)
				)
			)
		)
		(property "Device Type" "TP_PIONT-TP010CT020B030_PTH-TPA"
			(at -1.341882 0.996696 0)
			(unlocked yes)
			(layer "F.Fab")
			(hide yes)
			(effects
				(font
					(size 0.7874 0.5842)
					(thickness 0.000001)
				)
				(justify left)
			)
		)
		(duplicate_pad_numbers_are_jumpers no)
		(fp_poly
			(pts
				(arc
					(start 0.889 0)
					(mid -0.889 0)
					(end 0.889 0)
				)
			)
			(stroke
				(width 0)
				(type default)
			)
			(fill no)
			(layer "B.CrtYd")
		)
		(fp_poly
			(pts
				(arc
					(start 0.889 0)
					(mid -0.889 0)
					(end 0.889 0)
				)
			)
			(stroke
				(width 0)
				(type default)
			)
			(fill no)
			(layer "F.CrtYd")
		)
		(pad "1" thru_hole circle
			(at 0 0)
			(size 0.508 0.508)
			(drill 0.254)
			(layers "*.Cu" "*.Mask")
			(remove_unused_layers no)
			(net "MAC_ALARM")
			(clearance 0.1016)
			(padstack
				(mode front_inner_back)
				(layer "Inner"
					(shape circle)
					(size 0.508 0.508)
					(clearance 0.1016)
				)
				(layer "B.Cu"
					(shape circle)
					(size 0.762 0.762)
					(clearance -0.0254)
				)
			)
		)
	)
)
